(kicad_pcb
	(version 20260206)
	(generator "pcbnew")
	(generator_version "10.0")
	(general
		(thickness 1.6)
		(legacy_teardrops no)
	)
	(paper "A4")
	(title_block
		(title "Wiwynn_Tioga_Pass_MB.brd")
		(comment 1 "Tioga Pass / footprint 190 of 4770 (U2D1), pads 1429-1533 of 3647")
	)
	(layers
		(0 "F.Cu" signal "TOP")
		(4 "In1.Cu" signal "L2GND")
		(6 "In2.Cu" signal "L3")
		(8 "In3.Cu" signal "L4GND")
		(10 "In4.Cu" signal "L5")
		(12 "In5.Cu" signal "L6GND")
		(14 "In6.Cu" signal "L7VCC")
		(16 "In7.Cu" signal "L8VCC")
		(18 "In8.Cu" signal "L9GND")
		(20 "In9.Cu" signal "L10")
		(22 "In10.Cu" signal "L11GND")
		(24 "In11.Cu" signal "L12")
		(26 "In12.Cu" signal "L13GND")
		(2 "B.Cu" signal "BOTTOM")
		(9 "F.Adhes" user "F.Adhesive")
		(11 "B.Adhes" user "B.Adhesive")
		(13 "F.Paste" user "Package Geometry/Pastemask Top")
		(15 "B.Paste" user "Package Geometry/Pastemask Bottom")
		(5 "F.SilkS" user "Ref Des/Silkscreen Top")
		(7 "B.SilkS" user "Ref Des/Silkscreen Bottom")
		(1 "F.Mask" user "Board Geometry/Soldermask Top")
		(3 "B.Mask" user "Board Geometry/Soldermask Bottom")
		(17 "Dwgs.User" user "User.Drawings")
		(19 "Cmts.User" user "User.Comments")
		(21 "Eco1.User" user "User.Eco1")
		(23 "Eco2.User" user "User.Eco2")
		(25 "Edge.Cuts" user "Board Geometry/Outline")
		(27 "Margin" user)
		(31 "F.CrtYd" user "Package Geometry/Place Bound Top")
		(29 "B.CrtYd" user "Package Geometry/Place Bound Bottom")
		(35 "F.Fab" user "Ref Des/Assembly Top")
		(33 "B.Fab" user "Ref Des/Assembly Bottom")
	)
	(footprint ""
		(layer "F.Cu")
		(at 104.99979 -76.550012 180)
		(property "Reference" "U2D1"
			(at 25.19299 30.484318 0)
			(unlocked yes)
			(layer "F.SilkS")
			(effects
				(font
					(size 0.7874 0.5842)
					(thickness 0.1524)
				)
			)
		)
		(property "Value" ""
			(at 0 0 180)
			(layer "F.Fab")
			(effects
				(font
					(size 1.27 1.27)
				)
			)
		)
		(duplicate_pad_numbers_are_jumpers no)
		(pad "CF7" smd circle
			(at -32.099504 7.091172)
			(size 0.4318 0.4318)
			(layers "F.Cu" "F.Mask" "F.Paste")
			(net "TP_P3E_CPU1_PE2_RSR_RXP<5>")
		)
		(pad "CF9" smd circle
			(at -30.382464 7.091172)
			(size 0.4318 0.4318)
			(layers "F.Cu" "F.Mask" "F.Paste")
			(net "GND")
		)
		(pad "CF11" smd circle
			(at -28.665424 7.091172)
			(size 0.4318 0.4318)
			(layers "F.Cu" "F.Mask" "F.Paste")
			(net "TP_CPU1_UPI2_RSVD_DJ20")
		)
		(pad "CF13" smd circle
			(at -26.948384 7.091172)
			(size 0.4318 0.4318)
			(layers "F.Cu" "F.Mask" "F.Paste")
			(net "TP_CPU1_UPI2_RSVD_DH19")
		)
		(pad "CF15" smd circle
			(at -25.231598 7.091172)
			(size 0.4318 0.4318)
			(layers "F.Cu" "F.Mask" "F.Paste")
			(net "GND")
		)
		(pad "CF17" smd circle
			(at -23.514558 7.091172)
			(size 0.4318 0.4318)
			(layers "F.Cu" "F.Mask" "F.Paste")
			(net "GND")
		)
		(pad "CF19" smd circle
			(at -21.797518 7.091172)
			(size 0.4318 0.4318)
			(layers "F.Cu" "F.Mask" "F.Paste")
			(net "PVCCMCP_CPU1")
		)
		(pad "CF21" smd circle
			(at -20.080478 7.091172)
			(size 0.4318 0.4318)
			(layers "F.Cu" "F.Mask" "F.Paste")
			(net "PVCCMCP_CPU1")
		)
		(pad "CF23" smd circle
			(at -18.363438 7.091172)
			(size 0.4318 0.4318)
			(layers "F.Cu" "F.Mask" "F.Paste")
			(net "PVCCMCP_CPU1")
		)
		(pad "CF25" smd circle
			(at -16.646398 7.091172)
			(size 0.4318 0.4318)
			(layers "F.Cu" "F.Mask" "F.Paste")
			(net "RST_CD_CPU1_POR_N")
		)
		(pad "CF27" smd circle
			(at -14.929612 7.091172)
			(size 0.4318 0.4318)
			(layers "F.Cu" "F.Mask" "F.Paste")
			(net "PVCCIO_CPU1")
		)
		(pad "CF61" smd circle
			(at 15.787878 5.291074)
			(size 0.4318 0.4318)
			(layers "F.Cu" "F.Mask" "F.Paste")
			(net "PVCCIN_CPU1")
		)
		(pad "CF63" smd circle
			(at 17.504918 5.291074)
			(size 0.4318 0.4318)
			(layers "F.Cu" "F.Mask" "F.Paste")
			(net "GND")
		)
		(pad "CF65" smd circle
			(at 19.221958 5.291074)
			(size 0.4318 0.4318)
			(layers "F.Cu" "F.Mask" "F.Paste")
			(net "PVSA_CPU1")
		)
		(pad "CF67" smd circle
			(at 20.938998 5.291074)
			(size 0.4318 0.4318)
			(layers "F.Cu" "F.Mask" "F.Paste")
			(net "PVSA_CPU1")
		)
		(pad "CF69" smd circle
			(at 22.656038 5.291074)
			(size 0.4318 0.4318)
			(layers "F.Cu" "F.Mask" "F.Paste")
			(net "GND")
		)
		(pad "CF71" smd circle
			(at 24.373078 5.291074)
			(size 0.4318 0.4318)
			(layers "F.Cu" "F.Mask" "F.Paste")
			(net "GND")
		)
		(pad "CF73" smd circle
			(at 26.090118 5.291074)
			(size 0.4318 0.4318)
			(layers "F.Cu" "F.Mask" "F.Paste")
			(net "PVSA_CPU1")
		)
		(pad "CF75" smd circle
			(at 27.806904 5.291074)
			(size 0.4318 0.4318)
			(layers "F.Cu" "F.Mask" "F.Paste")
			(net "PVSA_CPU1")
		)
		(pad "CF77" smd circle
			(at 29.523944 5.291074)
			(size 0.4318 0.4318)
			(layers "F.Cu" "F.Mask" "F.Paste")
			(net "GND")
		)
		(pad "CF79" smd circle
			(at 31.240984 5.291074)
			(size 0.4318 0.4318)
			(layers "F.Cu" "F.Mask" "F.Paste")
			(net "TP_CPU1_RSVD_101")
		)
		(pad "CF81" smd circle
			(at 32.958024 5.291074)
			(size 0.4318 0.4318)
			(layers "F.Cu" "F.Mask" "F.Paste")
			(net "TP_CPU1_RSVD_100")
		)
		(pad "CF83" smd circle
			(at 34.675064 5.291074)
			(size 0.4318 0.4318)
			(layers "F.Cu" "F.Mask" "F.Paste")
			(net "GND")
		)
		(pad "CF85" smd custom
			(at 36.392104 5.291074 270)
			(size 0.10795 0.10795)
			(layers "F.Cu" "F.Mask" "F.Paste")
			(net "PVCCIN_CPU1")
			(options
				(clearance outline)
				(anchor circle)
			)
			(primitives
				(gr_poly
					(pts
						(arc
							(start 0.2159 -0.0381)
							(mid 0 -0.254)
							(end -0.2159 -0.0381)
						)
						(arc
							(start -0.2159 0.0381)
							(mid 0 0.254)
							(end 0.2159 0.0381)
						)
					)
					(width 0)
					(fill yes)
				)
			)
		)
		(pad "CG2" smd custom
			(at -36.392104 7.586726 90)
			(size 0.10795 0.10795)
			(layers "F.Cu" "F.Mask" "F.Paste")
			(net "TP_P3E_CPU1_PE2_RSR_TXN<6>")
			(options
				(clearance outline)
				(anchor circle)
			)
			(primitives
				(gr_poly
					(pts
						(arc
							(start 0.2159 -0.0381)
							(mid 0 -0.254)
							(end -0.2159 -0.0381)
						)
						(arc
							(start -0.2159 0.0381)
							(mid 0 0.254)
							(end 0.2159 0.0381)
						)
					)
					(width 0)
					(fill yes)
				)
			)
		)
		(pad "CG4" smd circle
			(at -34.675064 7.586726)
			(size 0.4318 0.4318)
			(layers "F.Cu" "F.Mask" "F.Paste")
			(net "TP_CPU1_DMI_TX_DN0")
		)
		(pad "CG6" smd circle
			(at -32.958024 7.586726)
			(size 0.4318 0.4318)
			(layers "F.Cu" "F.Mask" "F.Paste")
			(net "GND")
		)
		(pad "CG8" smd circle
			(at -31.240984 7.586726)
			(size 0.4318 0.4318)
			(layers "F.Cu" "F.Mask" "F.Paste")
			(net "TP_P3E_CPU1_PE2_RSR_RXN<5>")
		)
		(pad "CG10" smd circle
			(at -29.523944 7.586726)
			(size 0.4318 0.4318)
			(layers "F.Cu" "F.Mask" "F.Paste")
			(net "TP_CPU1_RSVD_99")
		)
		(pad "CG12" smd circle
			(at -27.806904 7.586726)
			(size 0.4318 0.4318)
			(layers "F.Cu" "F.Mask" "F.Paste")
			(net "TP_CPU1_UPI2_RSVD_DJ18")
		)
		(pad "CG14" smd circle
			(at -26.090118 7.586726)
			(size 0.4318 0.4318)
			(layers "F.Cu" "F.Mask" "F.Paste")
			(net "PVCCIO_CPU1")
		)
		(pad "CG16" smd circle
			(at -24.373078 7.586726)
			(size 0.4318 0.4318)
			(layers "F.Cu" "F.Mask" "F.Paste")
			(net "GND")
		)
		(pad "CG18" smd circle
			(at -22.656038 7.586726)
			(size 0.4318 0.4318)
			(layers "F.Cu" "F.Mask" "F.Paste")
			(net "GND")
		)
		(pad "CG20" smd circle
			(at -20.938998 7.586726)
			(size 0.4318 0.4318)
			(layers "F.Cu" "F.Mask" "F.Paste")
			(net "PVCCMCP_CPU1")
		)
		(pad "CG22" smd circle
			(at -19.221958 7.586726)
			(size 0.4318 0.4318)
			(layers "F.Cu" "F.Mask" "F.Paste")
			(net "GND")
		)
		(pad "CG24" smd circle
			(at -17.504918 7.586726)
			(size 0.4318 0.4318)
			(layers "F.Cu" "F.Mask" "F.Paste")
			(net "TP_CPU1_RSVD_97")
		)
		(pad "CG26" smd circle
			(at -15.787878 7.586726)
			(size 0.4318 0.4318)
			(layers "F.Cu" "F.Mask" "F.Paste")
			(net "PVCCMCP_CPU1")
		)
		(pad "CG60" smd circle
			(at 14.929612 5.786628)
			(size 0.508 0.508)
			(layers "F.Cu" "F.Mask" "F.Paste")
			(net "PVCCIN_CPU1")
		)
		(pad "CG62" smd circle
			(at 16.646398 5.786628)
			(size 0.4318 0.4318)
			(layers "F.Cu" "F.Mask" "F.Paste")
			(net "GND")
		)
		(pad "CG64" smd circle
			(at 18.363438 5.786628)
			(size 0.4318 0.4318)
			(layers "F.Cu" "F.Mask" "F.Paste")
			(net "PVSA_CPU1")
		)
		(pad "CG66" smd circle
			(at 20.080478 5.786628)
			(size 0.4318 0.4318)
			(layers "F.Cu" "F.Mask" "F.Paste")
			(net "PVSA_CPU1")
		)
		(pad "CG68" smd circle
			(at 21.797518 5.786628)
			(size 0.4318 0.4318)
			(layers "F.Cu" "F.Mask" "F.Paste")
			(net "GND")
		)
		(pad "CG70" smd circle
			(at 23.514558 5.786628)
			(size 0.4318 0.4318)
			(layers "F.Cu" "F.Mask" "F.Paste")
			(net "M_M_DQS_DP<17>")
		)
		(pad "CG72" smd circle
			(at 25.231598 5.786628)
			(size 0.4318 0.4318)
			(layers "F.Cu" "F.Mask" "F.Paste")
			(net "GND")
		)
		(pad "CG74" smd circle
			(at 26.948384 5.786628)
			(size 0.4318 0.4318)
			(layers "F.Cu" "F.Mask" "F.Paste")
			(net "PVSA_CPU1")
		)
		(pad "CG76" smd circle
			(at 28.665424 5.786628)
			(size 0.4318 0.4318)
			(layers "F.Cu" "F.Mask" "F.Paste")
			(net "VSENSE_PVSA_CPU1_SKT_VRTN")
		)
		(pad "CG78" smd circle
			(at 30.382464 5.786628)
			(size 0.4318 0.4318)
			(layers "F.Cu" "F.Mask" "F.Paste")
			(net "TP_CPU1_RSVD_95")
		)
		(pad "CG80" smd circle
			(at 32.099504 5.786628)
			(size 0.4318 0.4318)
			(layers "F.Cu" "F.Mask" "F.Paste")
			(net "GND")
		)
		(pad "CG82" smd circle
			(at 33.816544 5.786628)
			(size 0.4318 0.4318)
			(layers "F.Cu" "F.Mask" "F.Paste")
			(net "TP_CPU1_RSVD_94")
		)
		(pad "CG84" smd circle
			(at 35.533584 5.786628)
			(size 0.4318 0.4318)
			(layers "F.Cu" "F.Mask" "F.Paste")
			(net "PVCCIN_CPU1")
		)
		(pad "CH1" smd custom
			(at -37.250624 8.081772 90)
			(size 0.10795 0.10795)
			(layers "F.Cu" "F.Mask" "F.Paste")
			(net "GND")
			(options
				(clearance outline)
				(anchor circle)
			)
			(primitives
				(gr_poly
					(pts
						(arc
							(start 0.2159 -0.0381)
							(mid 0 -0.254)
							(end -0.2159 -0.0381)
						)
						(arc
							(start -0.2159 0.0381)
							(mid 0 0.254)
							(end 0.2159 0.0381)
						)
					)
					(width 0)
					(fill yes)
				)
			)
		)
		(pad "CH3" smd circle
			(at -35.533584 8.081772)
			(size 0.4318 0.4318)
			(layers "F.Cu" "F.Mask" "F.Paste")
			(net "GND")
		)
		(pad "CH5" smd circle
			(at -33.816544 8.081772)
			(size 0.4318 0.4318)
			(layers "F.Cu" "F.Mask" "F.Paste")
			(net "TP_CPU1_DMI_TX_DP0")
		)
		(pad "CH7" smd circle
			(at -32.099504 8.081772)
			(size 0.4318 0.4318)
			(layers "F.Cu" "F.Mask" "F.Paste")
			(net "TP_P3E_CPU1_PE2_RSR_RXP<4>")
		)
		(pad "CH9" smd circle
			(at -30.382464 8.081772)
			(size 0.4318 0.4318)
			(layers "F.Cu" "F.Mask" "F.Paste")
			(net "PVCCIO_CPU1")
		)
		(pad "CH11" smd circle
			(at -28.665424 8.081772)
			(size 0.4318 0.4318)
			(layers "F.Cu" "F.Mask" "F.Paste")
			(net "TP_CPU1_UPI2_RSVD_DG20")
		)
		(pad "CH13" smd circle
			(at -26.948384 8.081772)
			(size 0.4318 0.4318)
			(layers "F.Cu" "F.Mask" "F.Paste")
			(net "TP_CPU1_UPI2_RSVD_DH17")
		)
		(pad "CH15" smd circle
			(at -25.231598 8.081772)
			(size 0.4318 0.4318)
			(layers "F.Cu" "F.Mask" "F.Paste")
			(net "GND")
		)
		(pad "CH17" smd circle
			(at -23.514558 8.081772)
			(size 0.4318 0.4318)
			(layers "F.Cu" "F.Mask" "F.Paste")
			(net "GND")
		)
		(pad "CH19" smd circle
			(at -21.797518 8.081772)
			(size 0.4318 0.4318)
			(layers "F.Cu" "F.Mask" "F.Paste")
			(net "GND")
		)
		(pad "CH21" smd circle
			(at -20.080478 8.081772)
			(size 0.4318 0.4318)
			(layers "F.Cu" "F.Mask" "F.Paste")
			(net "PVCCMCP_CPU1")
		)
		(pad "CH23" smd circle
			(at -18.363438 8.081772)
			(size 0.4318 0.4318)
			(layers "F.Cu" "F.Mask" "F.Paste")
			(net "PVCCMCP_CPU1")
		)
		(pad "CH25" smd circle
			(at -16.646398 8.081772)
			(size 0.4318 0.4318)
			(layers "F.Cu" "F.Mask" "F.Paste")
			(net "TP_CPU1_RSVD_91")
		)
		(pad "CH27" smd circle
			(at -14.929612 8.081772)
			(size 0.4318 0.4318)
			(layers "F.Cu" "F.Mask" "F.Paste")
			(net "PVCCIO_CPU1")
		)
		(pad "CH61" smd circle
			(at 15.787878 6.281928)
			(size 0.4318 0.4318)
			(layers "F.Cu" "F.Mask" "F.Paste")
			(net "PVCCIN_CPU1")
		)
		(pad "CH63" smd circle
			(at 17.504918 6.281928)
			(size 0.4318 0.4318)
			(layers "F.Cu" "F.Mask" "F.Paste")
			(net "GND")
		)
		(pad "CH65" smd circle
			(at 19.221958 6.281928)
			(size 0.4318 0.4318)
			(layers "F.Cu" "F.Mask" "F.Paste")
			(net "PVSA_CPU1")
		)
		(pad "CH67" smd circle
			(at 20.938998 6.281928)
			(size 0.4318 0.4318)
			(layers "F.Cu" "F.Mask" "F.Paste")
			(net "GND")
		)
		(pad "CH69" smd circle
			(at 22.656038 6.281928)
			(size 0.4318 0.4318)
			(layers "F.Cu" "F.Mask" "F.Paste")
			(net "M_M_ECC<6>")
		)
		(pad "CH71" smd circle
			(at 24.373078 6.281928)
			(size 0.4318 0.4318)
			(layers "F.Cu" "F.Mask" "F.Paste")
			(net "M_M_ECC<0>")
		)
		(pad "CH73" smd circle
			(at 26.090118 6.281928)
			(size 0.4318 0.4318)
			(layers "F.Cu" "F.Mask" "F.Paste")
			(net "GND")
		)
		(pad "CH75" smd circle
			(at 27.806904 6.281928)
			(size 0.4318 0.4318)
			(layers "F.Cu" "F.Mask" "F.Paste")
			(net "PVSA_CPU1")
		)
		(pad "CH77" smd circle
			(at 29.523944 6.281928)
			(size 0.4318 0.4318)
			(layers "F.Cu" "F.Mask" "F.Paste")
			(net "TP_CPU1_RSVD_90")
		)
		(pad "CH79" smd circle
			(at 31.240984 6.281928)
			(size 0.4318 0.4318)
			(layers "F.Cu" "F.Mask" "F.Paste")
			(net "GND")
		)
		(pad "CH81" smd circle
			(at 32.958024 6.281928)
			(size 0.4318 0.4318)
			(layers "F.Cu" "F.Mask" "F.Paste")
			(net "GND")
		)
		(pad "CH83" smd circle
			(at 34.675064 6.281928)
			(size 0.4318 0.4318)
			(layers "F.Cu" "F.Mask" "F.Paste")
			(net "GND")
		)
		(pad "CH85" smd custom
			(at 36.392104 6.281928 270)
			(size 0.10795 0.10795)
			(layers "F.Cu" "F.Mask" "F.Paste")
			(net "PVCCIN_CPU1")
			(options
				(clearance outline)
				(anchor circle)
			)
			(primitives
				(gr_poly
					(pts
						(arc
							(start 0.2159 -0.0381)
							(mid 0 -0.254)
							(end -0.2159 -0.0381)
						)
						(arc
							(start -0.2159 0.0381)
							(mid 0 0.254)
							(end 0.2159 0.0381)
						)
					)
					(width 0)
					(fill yes)
				)
			)
		)
		(pad "CJ2" smd circle
			(at -36.392104 8.577326)
			(size 0.4318 0.4318)
			(layers "F.Cu" "F.Mask" "F.Paste")
			(net "GND")
		)
		(pad "CJ4" smd circle
			(at -34.675064 8.577326)
			(size 0.4318 0.4318)
			(layers "F.Cu" "F.Mask" "F.Paste")
			(net "TP_CPU1_DMI_TX_DN1")
		)
		(pad "CJ6" smd circle
			(at -32.958024 8.577326)
			(size 0.4318 0.4318)
			(layers "F.Cu" "F.Mask" "F.Paste")
			(net "GND")
		)
		(pad "CJ8" smd circle
			(at -31.240984 8.577326)
			(size 0.4318 0.4318)
			(layers "F.Cu" "F.Mask" "F.Paste")
			(net "GND")
		)
		(pad "CJ10" smd circle
			(at -29.523944 8.577326)
			(size 0.4318 0.4318)
			(layers "F.Cu" "F.Mask" "F.Paste")
			(net "GND")
		)
		(pad "CJ12" smd circle
			(at -27.806904 8.577326)
			(size 0.4318 0.4318)
			(layers "F.Cu" "F.Mask" "F.Paste")
			(net "GND")
		)
		(pad "CJ14" smd circle
			(at -26.090118 8.577326)
			(size 0.4318 0.4318)
			(layers "F.Cu" "F.Mask" "F.Paste")
			(net "TP_CPU1_UPI2_RSVD_DK17")
		)
		(pad "CJ16" smd circle
			(at -24.373078 8.577326)
			(size 0.4318 0.4318)
			(layers "F.Cu" "F.Mask" "F.Paste")
			(net "GND")
		)
		(pad "CJ18" smd circle
			(at -22.656038 8.577326)
			(size 0.4318 0.4318)
			(layers "F.Cu" "F.Mask" "F.Paste")
			(net "GND")
		)
		(pad "CJ20" smd circle
			(at -20.938998 8.577326)
			(size 0.4318 0.4318)
			(layers "F.Cu" "F.Mask" "F.Paste")
			(net "PVCCMCP_CPU1")
		)
		(pad "CJ22" smd circle
			(at -19.221958 8.577326)
			(size 0.4318 0.4318)
			(layers "F.Cu" "F.Mask" "F.Paste")
			(net "PVCCMCP_CPU1")
		)
		(pad "CJ24" smd circle
			(at -17.504918 8.577326)
			(size 0.4318 0.4318)
			(layers "F.Cu" "F.Mask" "F.Paste")
			(net "PVCCMCP_CPU1")
		)
		(pad "CJ26" smd circle
			(at -15.787878 8.577326)
			(size 0.4318 0.4318)
			(layers "F.Cu" "F.Mask" "F.Paste")
			(net "PVCCMCP_CPU1")
		)
		(pad "CJ28" smd circle
			(at -14.071092 8.577326)
			(size 0.4318 0.4318)
			(layers "F.Cu" "F.Mask" "F.Paste")
			(net "PVCCIO_CPU1")
		)
		(pad "CJ60" smd circle
			(at 14.929612 6.777228)
			(size 0.508 0.508)
			(layers "F.Cu" "F.Mask" "F.Paste")
			(net "PVCCIN_CPU1")
		)
		(pad "CJ62" smd circle
			(at 16.646398 6.777228)
			(size 0.4318 0.4318)
			(layers "F.Cu" "F.Mask" "F.Paste")
			(net "GND")
		)
		(pad "CJ64" smd circle
			(at 18.363438 6.777228)
			(size 0.4318 0.4318)
			(layers "F.Cu" "F.Mask" "F.Paste")
			(net "PVSA_CPU1")
		)
		(pad "CJ66" smd circle
			(at 20.080478 6.777228)
			(size 0.4318 0.4318)
			(layers "F.Cu" "F.Mask" "F.Paste")
			(net "PVSA_CPU1")
		)
		(pad "CJ68" smd circle
			(at 21.797518 6.777228)
			(size 0.4318 0.4318)
			(layers "F.Cu" "F.Mask" "F.Paste")
			(net "M_M_ECC<2>")
		)
		(pad "CJ70" smd circle
			(at 23.514558 6.777228)
			(size 0.4318 0.4318)
			(layers "F.Cu" "F.Mask" "F.Paste")
			(net "M_M_DQS_DN<17>")
		)
		(pad "CJ72" smd circle
			(at 25.231598 6.777228)
			(size 0.4318 0.4318)
			(layers "F.Cu" "F.Mask" "F.Paste")
			(net "M_M_ECC<4>")
		)
		(pad "CJ74" smd circle
			(at 26.948384 6.777228)
			(size 0.4318 0.4318)
			(layers "F.Cu" "F.Mask" "F.Paste")
			(net "GND")
		)
		(pad "CJ76" smd circle
			(at 28.665424 6.777228)
			(size 0.4318 0.4318)
			(layers "F.Cu" "F.Mask" "F.Paste")
			(net "GND")
		)
		(pad "CJ78" smd circle
			(at 30.382464 6.777228)
			(size 0.4318 0.4318)
			(layers "F.Cu" "F.Mask" "F.Paste")
			(net "GND")
		)
		(pad "CJ80" smd circle
			(at 32.099504 6.777228)
			(size 0.4318 0.4318)
			(layers "F.Cu" "F.Mask" "F.Paste")
			(net "M_L_DQ<5>")
		)
		(pad "CJ82" smd circle
			(at 33.816544 6.777228)
			(size 0.4318 0.4318)
			(layers "F.Cu" "F.Mask" "F.Paste")
			(net "GND")
		)
		(pad "CJ84" smd circle
			(at 35.533584 6.777228)
			(size 0.4318 0.4318)
			(layers "F.Cu" "F.Mask" "F.Paste")
			(net "GND")
		)
		(pad "CJ86" smd custom
			(at 37.250624 6.777228 270)
			(size 0.10795 0.10795)
			(layers "F.Cu" "F.Mask" "F.Paste")
			(net "GND")
			(options
				(clearance outline)
				(anchor circle)
			)
			(primitives
				(gr_poly
					(pts
						(arc
							(start 0.2159 -0.0381)
							(mid 0 -0.254)
							(end -0.2159 -0.0381)
						)
						(arc
							(start -0.2159 0.0381)
							(mid 0 0.254)
							(end 0.2159 0.0381)
						)
					)
					(width 0)
					(fill yes)
				)
			)
		)
	)
)
